(kicad_pcb
	(version 20241229)
	(generator "pcbnew")
	(generator_version "9.0")
	(general
		(thickness 1.711)
		(legacy_teardrops no)
	)
	(paper "A4")
	(title_block
		(title "Antmicro Baseboard for Jetson AGX Thor")
		(date "2026-02-18")
		(rev "1.1.0")
		(company "Antmicro Ltd")
		(comment 1 "www.antmicro.com")
		(comment 9 "footprints 426-429 of 1170")
	)
	(layers
		(0 "F.Cu" signal)
		(4 "In1.Cu" signal)
		(6 "In2.Cu" signal)
		(8 "In3.Cu" signal)
		(10 "In4.Cu" jumper)
		(12 "In5.Cu" signal)
		(14 "In6.Cu" signal)
		(16 "In7.Cu" signal)
		(18 "In8.Cu" signal)
		(2 "B.Cu" signal)
		(9 "F.Adhes" user "F.Adhesive")
		(11 "B.Adhes" user "B.Adhesive")
		(13 "F.Paste" user)
		(15 "B.Paste" user)
		(5 "F.SilkS" user "F.Silkscreen")
		(7 "B.SilkS" user "B.Silkscreen")
		(1 "F.Mask" user)
		(3 "B.Mask" user)
		(17 "Dwgs.User" user "User.Drawings")
		(19 "Cmts.User" user "User.Comments")
		(21 "Eco1.User" user "User.Eco1")
		(23 "Eco2.User" user "User.Eco2")
		(25 "Edge.Cuts" user)
		(27 "Margin" user)
		(31 "F.CrtYd" user "F.Courtyard")
		(29 "B.CrtYd" user "B.Courtyard")
		(35 "F.Fab" user)
		(33 "B.Fab" user)
	)
	(footprint "antmicro-footprints:C_0402_1005Metric"
		(layer "F.Cu")
		(at 89.1 99.8)
		(descr "Capacitor SMD 0402")
		(tags "capacitor SMD 0402")
		(property "Reference" "C337"
			(at -3.82 0.449999 0)
			(layer "F.SilkS")
			(effects
				(font
					(size 0.7 0.7)
					(thickness 0.15)
				)
				(justify left bottom)
			)
		)
		(property "Value" "C_100n_0402"
			(at -1.022927 2.155213 0)
			(layer "F.Fab")
			(effects
				(font
					(size 0.7 0.7)
					(thickness 0.15)
				)
				(justify left bottom)
			)
		)
		(property "Datasheet" "https://www.murata.com/products/productdetail?partno=GRM155R61H104KE14%23"
			(at 0 0 0)
			(layer "F.Fab")
			(hide yes)
			(effects
				(font
					(size 1.27 1.27)
					(thickness 0.15)
				)
			)
		)
		(property "Description" "SMD Multilayer Ceramic Capacitor, 0.1 µF, 50 V, 0402 [1005 Metric], ± 10%, X5R, GRM Series"
			(at 0 0 0)
			(layer "F.Fab")
			(hide yes)
			(effects
				(font
					(size 1.27 1.27)
					(thickness 0.15)
				)
			)
		)
		(property "Manufacturer" "Murata"
			(at 0 0 0)
			(unlocked yes)
			(layer "F.Fab")
			(hide yes)
			(effects
				(font
					(size 1 1)
					(thickness 0.15)
				)
			)
		)
		(property "MPN" "GRM155R61H104KE14D"
			(at 0 0 0)
			(unlocked yes)
			(layer "F.Fab")
			(hide yes)
			(effects
				(font
					(size 1 1)
					(thickness 0.15)
				)
			)
		)
		(property "Val" "100n"
			(at 0 0 0)
			(unlocked yes)
			(layer "F.Fab")
			(hide yes)
			(effects
				(font
					(size 1 1)
					(thickness 0.15)
				)
			)
		)
		(property "License" "Apache-2.0"
			(at 0 0 0)
			(unlocked yes)
			(layer "F.Fab")
			(hide yes)
			(effects
				(font
					(size 1 1)
					(thickness 0.15)
				)
			)
		)
		(property "Author" "Antmicro"
			(at 0 0 0)
			(unlocked yes)
			(layer "F.Fab")
			(hide yes)
			(effects
				(font
					(size 1 1)
					(thickness 0.15)
				)
			)
		)
		(property "Voltage" "50V"
			(at 0 0 0)
			(unlocked yes)
			(layer "F.Fab")
			(hide yes)
			(effects
				(font
					(size 1 1)
					(thickness 0.15)
				)
			)
		)
		(property "Dielectric" "X5R"
			(at 0 0 0)
			(unlocked yes)
			(layer "F.Fab")
			(hide yes)
			(effects
				(font
					(size 1 1)
					(thickness 0.15)
				)
			)
		)
		(sheetname "/SoM_IO2/")
		(sheetfile "som_io2.kicad_sch")
		(attr smd)
		(fp_poly
			(pts
				(xy -0.925 -0.47) (xy 0.925 -0.47) (xy 0.925 0.47) (xy -0.925 0.47)
			)
			(stroke
				(width 0.05)
				(type default)
			)
			(fill no)
			(layer "F.CrtYd")
		)
		(fp_line
			(start -0.494 -0.25)
			(end 0.504 -0.25)
			(stroke
				(width 0.15)
				(type solid)
			)
			(layer "F.Fab")
		)
		(fp_line
			(start -0.494 0.248)
			(end -0.494 -0.25)
			(stroke
				(width 0.15)
				(type solid)
			)
			(layer "F.Fab")
		)
		(fp_line
			(start 0.504 -0.25)
			(end 0.504 0.248)
			(stroke
				(width 0.15)
				(type solid)
			)
			(layer "F.Fab")
		)
		(fp_line
			(start 0.504 0.248)
			(end -0.494 0.248)
			(stroke
				(width 0.15)
				(type solid)
			)
			(layer "F.Fab")
		)
		(fp_text user "Author: Antmicro"
			(at -0.939 3.399 0)
			(layer "F.Fab")
			(effects
				(font
					(size 0.7 0.7)
					(thickness 0.15)
				)
				(justify left bottom)
			)
		)
		(fp_text user "License: Apache-2.0"
			(at -0.939 5.799 0)
			(layer "F.Fab")
			(effects
				(font
					(size 0.7 0.7)
					(thickness 0.15)
				)
				(justify left bottom)
			)
		)
		(fp_text user "${REFERENCE}"
			(at -0.939 4.599 0)
			(layer "F.Fab")
			(effects
				(font
					(size 0.7 0.7)
					(thickness 0.15)
				)
				(justify left bottom)
			)
		)
		(pad "1" smd roundrect
			(at -0.48 0)
			(size 0.59 0.64)
			(layers "F.Cu" "F.Mask" "F.Paste")
			(roundrect_rratio 0.25)
			(net 640 "/Expansion connector/DP2.TX3+")
			(pintype "passive")
		)
		(pad "2" smd roundrect
			(at 0.48 0)
			(size 0.59 0.64)
			(layers "F.Cu" "F.Mask" "F.Paste")
			(roundrect_rratio 0.25)
			(net 1257 "/SoM_IO2/DP2.TX3_C+")
			(pintype "passive")
		)
	)
	(footprint "antmicro-footprints:R_0402_1005Metric"
		(layer "F.Cu")
		(at 111.22 61.79 90)
		(descr "Resistor SMD 0402")
		(tags "resistor SMD 0402")
		(property "Reference" "R68"
			(at -4.89 0.14 90)
			(layer "F.SilkS")
			(effects
				(font
					(size 0.7 0.7)
					(thickness 0.15)
				)
				(justify left bottom)
			)
		)
		(property "Value" "R_10k_0402"
			(at -1.011843 1.772046 90)
			(layer "F.Fab")
			(effects
				(font
					(size 0.7 0.7)
					(thickness 0.15)
				)
				(justify left bottom)
			)
		)
		(property "Datasheet" "https://www.bourns.com/docs/product-datasheets/cr.pdf"
			(at 0 0 90)
			(layer "F.Fab")
			(hide yes)
			(effects
				(font
					(size 1.27 1.27)
					(thickness 0.15)
				)
			)
		)
		(property "Description" "SMD Chip Resistor, 10 kohm, ± 1%, 62.5 mW, 0402 [1005 Metric], Thick Film, General Purpose"
			(at 0 0 90)
			(layer "F.Fab")
			(hide yes)
			(effects
				(font
					(size 1.27 1.27)
					(thickness 0.15)
				)
			)
		)
		(property "Manufacturer" "Bourns"
			(at 0 0 90)
			(unlocked yes)
			(layer "F.Fab")
			(hide yes)
			(effects
				(font
					(size 1 1)
					(thickness 0.15)
				)
			)
		)
		(property "MPN" "CR0402-FX-1002GLF"
			(at 0 0 90)
			(unlocked yes)
			(layer "F.Fab")
			(hide yes)
			(effects
				(font
					(size 1 1)
					(thickness 0.15)
				)
			)
		)
		(property "Val" "10k"
			(at 0 0 90)
			(unlocked yes)
			(layer "F.Fab")
			(hide yes)
			(effects
				(font
					(size 1 1)
					(thickness 0.15)
				)
			)
		)
		(property "License" "Apache-2.0"
			(at 0 0 90)
			(unlocked yes)
			(layer "F.Fab")
			(hide yes)
			(effects
				(font
					(size 1 1)
					(thickness 0.15)
				)
			)
		)
		(property "Author" "Antmicro"
			(at 0 0 90)
			(unlocked yes)
			(layer "F.Fab")
			(hide yes)
			(effects
				(font
					(size 1 1)
					(thickness 0.15)
				)
			)
		)
		(property "Tolerance" "1%"
			(at 0 0 90)
			(unlocked yes)
			(layer "F.Fab")
			(hide yes)
			(effects
				(font
					(size 1 1)
					(thickness 0.15)
				)
			)
		)
		(sheetname "/SoM_Power/")
		(sheetfile "som_power.kicad_sch")
		(attr smd)
		(fp_poly
			(pts
				(xy -0.925 -0.47) (xy 0.925 -0.47) (xy 0.925 0.47) (xy -0.925 0.47)
			)
			(stroke
				(width 0.05)
				(type default)
			)
			(fill no)
			(layer "F.CrtYd")
		)
		(fp_poly
			(pts
				(xy -0.5 -0.25) (xy 0.5 -0.25) (xy 0.5 0.25) (xy -0.5 0.25)
			)
			(stroke
				(width 0.15)
				(type solid)
			)
			(fill no)
			(layer "F.Fab")
		)
		(fp_text user "License: Apache-2.0"
			(at -0.949999 5.169 90)
			(layer "F.Fab")
			(effects
				(font
					(size 0.7 0.7)
					(thickness 0.15)
				)
				(justify left bottom)
			)
		)
		(fp_text user "${REFERENCE}"
			(at -0.95 3.168 90)
			(layer "F.Fab")
			(effects
				(font
					(size 0.7 0.7)
					(thickness 0.15)
				)
				(justify left bottom)
			)
		)
		(fp_text user "Author: Antmicro"
			(at -0.95 4.169 90)
			(layer "F.Fab")
			(effects
				(font
					(size 0.7 0.7)
					(thickness 0.15)
				)
				(justify left bottom)
			)
		)
		(pad "1" smd roundrect
			(at -0.48 0 90)
			(size 0.59 0.64)
			(layers "F.Cu" "F.Mask" "F.Paste")
			(roundrect_rratio 0.25)
			(net 1392 "Net-(Q6-D)")
			(pintype "passive")
		)
		(pad "2" smd roundrect
			(at 0.48 0 90)
			(size 0.59 0.64)
			(layers "F.Cu" "F.Mask" "F.Paste")
			(roundrect_rratio 0.25)
			(net 491 "+5V_AON")
			(pintype "passive")
		)
	)
	(footprint "antmicro-footprints:SOT-523"
		(layer "F.Cu")
		(at 70.75 55.75)
		(property "Reference" "Q20"
			(at 3.25 -1.45 0)
			(layer "F.SilkS")
			(effects
				(font
					(size 0.7 0.7)
					(thickness 0.15)
				)
				(justify right top)
			)
		)
		(property "Value" "DMG1012T-7"
			(at 0.1 1.824 0)
			(layer "F.Fab")
			(effects
				(font
					(size 0.7 0.7)
					(thickness 0.15)
				)
				(justify left bottom)
			)
		)
		(property "Datasheet" "https://www.diodes.com/assets/Datasheets/ds31783.pdf"
			(at 0 0 0)
			(layer "F.Fab")
			(hide yes)
			(effects
				(font
					(size 1.27 1.27)
					(thickness 0.15)
				)
			)
		)
		(property "Description" "Power MOSFET, N Channel, 20 V, 630 mA, 0.3 ohm, SOT-523, Surface Mount"
			(at 0 0 0)
			(layer "F.Fab")
			(hide yes)
			(effects
				(font
					(size 1.27 1.27)
					(thickness 0.15)
				)
			)
		)
		(property "MPN" "DMG1012T-7"
			(at 0 0 0)
			(unlocked yes)
			(layer "F.Fab")
			(hide yes)
			(effects
				(font
					(size 1 1)
					(thickness 0.15)
				)
			)
		)
		(property "Manufacturer" "Diodes Incorporated"
			(at 0 0 0)
			(unlocked yes)
			(layer "F.Fab")
			(hide yes)
			(effects
				(font
					(size 1 1)
					(thickness 0.15)
				)
			)
		)
		(property "Author" "Antmicro"
			(at 0 0 0)
			(unlocked yes)
			(layer "F.Fab")
			(hide yes)
			(effects
				(font
					(size 1 1)
					(thickness 0.15)
				)
			)
		)
		(property "License" "Apache-2.0"
			(at 0 0 0)
			(unlocked yes)
			(layer "F.Fab")
			(hide yes)
			(effects
				(font
					(size 1 1)
					(thickness 0.15)
				)
			)
		)
		(sheetname "/SoM_Power/")
		(sheetfile "som_power.kicad_sch")
		(attr smd)
		(fp_line
			(start -0.927 -0.351)
			(end -0.725 -0.551)
			(stroke
				(width 0.15)
				(type solid)
			)
			(layer "F.SilkS")
		)
		(fp_line
			(start -0.927 -0.051)
			(end -0.927 -0.351)
			(stroke
				(width 0.15)
				(type solid)
			)
			(layer "F.SilkS")
		)
		(fp_line
			(start -0.725 -0.551)
			(end -0.277 -0.551)
			(stroke
				(width 0.15)
				(type solid)
			)
			(layer "F.SilkS")
		)
		(fp_line
			(start -0.277 -0.551)
			(end -0.277 -0.75)
			(stroke
				(width 0.15)
				(type solid)
			)
			(layer "F.SilkS")
		)
		(fp_circle
			(center -0.9652 0.9652)
			(end -0.9152 0.9652)
			(stroke
				(width 0.15)
				(type solid)
			)
			(fill yes)
			(layer "F.SilkS")
		)
		(fp_line
			(start -1.12 -1.16)
			(end -1.12 1.15)
			(stroke
				(width 0.05)
				(type solid)
			)
			(layer "F.CrtYd")
		)
		(fp_line
			(start -1.12 -1.16)
			(end 1.1 -1.16)
			(stroke
				(width 0.05)
				(type solid)
			)
			(layer "F.CrtYd")
		)
		(fp_line
			(start -1.12 1.15)
			(end 1.1 1.15)
			(stroke
				(width 0.05)
				(type solid)
			)
			(layer "F.CrtYd")
		)
		(fp_line
			(start 1.1 -1.16)
			(end 1.1 1.15)
			(stroke
				(width 0.05)
				(type solid)
			)
			(layer "F.CrtYd")
		)
		(fp_line
			(start -0.802 -0.276)
			(end -0.802 0.424)
			(stroke
				(width 0.15)
				(type solid)
			)
			(layer "F.Fab")
		)
		(fp_line
			(start -0.652 -0.425)
			(end -0.802 -0.276)
			(stroke
				(width 0.15)
				(type solid)
			)
			(layer "F.Fab")
		)
		(fp_line
			(start 0.8 -0.425)
			(end -0.652 -0.425)
			(stroke
				(width 0.15)
				(type solid)
			)
			(layer "F.Fab")
		)
		(fp_line
			(start 0.8 -0.425)
			(end 0.8 0.424)
			(stroke
				(width 0.15)
				(type solid)
			)
			(layer "F.Fab")
		)
		(fp_line
			(start 0.8 0.424)
			(end -0.802 0.424)
			(stroke
				(width 0.15)
				(type solid)
			)
			(layer "F.Fab")
		)
		(fp_circle
			(center -0.9652 0.9652)
			(end -0.9144 0.9652)
			(stroke
				(width 0.15)
				(type solid)
			)
			(fill no)
			(layer "F.Fab")
		)
		(fp_text user "Author: Antmicro"
			(at -1.12 6.224 0)
			(layer "F.Fab")
			(effects
				(font
					(size 0.7 0.7)
					(thickness 0.15)
				)
				(justify left bottom)
			)
		)
		(fp_text user "License: Apache-2.0"
			(at -1.12 5.024 0)
			(layer "F.Fab")
			(effects
				(font
					(size 0.7 0.7)
					(thickness 0.15)
				)
				(justify left bottom)
			)
		)
		(fp_text user "${REFERENCE}"
			(at -1.12 3.824 0)
			(layer "F.Fab")
			(effects
				(font
					(size 0.7 0.7)
					(thickness 0.15)
				)
				(justify left bottom)
			)
		)
		(pad "1" smd rect
			(at -0.5 0.65)
			(size 0.4 0.51)
			(layers "F.Cu" "F.Mask" "F.Paste")
			(net 1285 "/SoM_Power/VIN_PWR_ON")
			(pinfunction "G")
			(pintype "input")
		)
		(pad "2" smd rect
			(at 0.498 0.65)
			(size 0.4 0.51)
			(layers "F.Cu" "F.Mask" "F.Paste")
			(net 1 "GND")
			(pinfunction "S")
			(pintype "passive")
		)
		(pad "3" smd rect
			(at 0 -0.652)
			(size 0.4 0.51)
			(layers "F.Cu" "F.Mask" "F.Paste")
			(net 550 "Net-(D52-C)")
			(pinfunction "D")
			(pintype "passive")
		)
	)
	(footprint "antmicro-footprints:C_0805_2012Metric"
		(layer "F.Cu")
		(at 170.9 142.39 90)
		(descr "Capacitor SMD 0805")
		(tags "capacitor SMD 0805")
		(property "Reference" "C28"
			(at 1.99 -1.2 180)
			(layer "F.SilkS")
			(effects
				(font
					(size 0.7 0.7)
					(thickness 0.15)
				)
				(justify left bottom)
			)
		)
		(property "Value" "C_22u_25V_0805"
			(at -2.055717 1.963152 90)
			(layer "F.Fab")
			(effects
				(font
					(size 0.7 0.7)
					(thickness 0.15)
				)
				(justify left bottom)
			)
		)
		(property "Datasheet" "https://product.samsungsem.com/mlcc/CL21A226MAYNNN.do"
			(at 0 0 90)
			(layer "F.Fab")
			(hide yes)
			(effects
				(font
					(size 1.27 1.27)
					(thickness 0.15)
				)
			)
		)
		(property "Description" "SMT Multilayer Ceramic Capacitor, 22uF, +/-20%, 25V, X5R, 0805 [2012 Metric]"
			(at 0 0 90)
			(layer "F.Fab")
			(hide yes)
			(effects
				(font
					(size 1.27 1.27)
					(thickness 0.15)
				)
			)
		)
		(property "Manufacturer" "Samsung Electro-Mechanics"
			(at 0 0 90)
			(unlocked yes)
			(layer "F.Fab")
			(hide yes)
			(effects
				(font
					(size 1 1)
					(thickness 0.15)
				)
			)
		)
		(property "MPN" "CL21A226MAYNNNE"
			(at 0 0 90)
			(unlocked yes)
			(layer "F.Fab")
			(hide yes)
			(effects
				(font
					(size 1 1)
					(thickness 0.15)
				)
			)
		)
		(property "Val" "22u"
			(at 0 0 90)
			(unlocked yes)
			(layer "F.Fab")
			(hide yes)
			(effects
				(font
					(size 1 1)
					(thickness 0.15)
				)
			)
		)
		(property "License" "Apache-2.0"
			(at 0 0 90)
			(unlocked yes)
			(layer "F.Fab")
			(hide yes)
			(effects
				(font
					(size 1 1)
					(thickness 0.15)
				)
			)
		)
		(property "Author" "Antmicro"
			(at 0 0 90)
			(unlocked yes)
			(layer "F.Fab")
			(hide yes)
			(effects
				(font
					(size 1 1)
					(thickness 0.15)
				)
			)
		)
		(property "Voltage" "25V"
			(at 0 0 90)
			(unlocked yes)
			(layer "F.Fab")
			(hide yes)
			(effects
				(font
					(size 1 1)
					(thickness 0.15)
				)
			)
		)
		(property "Dielectric" "X5R"
			(at 0 0 90)
			(unlocked yes)
			(layer "F.Fab")
			(hide yes)
			(effects
				(font
					(size 1 1)
					(thickness 0.15)
				)
			)
		)
		(property "Public" "False"
			(at 0 0 90)
			(unlocked yes)
			(layer "F.Fab")
			(hide yes)
			(effects
				(font
					(size 1 1)
					(thickness 0.15)
				)
			)
		)
		(sheetname "/DCDC/")
		(sheetfile "dcdc.kicad_sch")
		(attr smd)
		(fp_line
			(start -0.3 -0.7)
			(end 0.3 -0.7)
			(stroke
				(width 0.15)
				(type solid)
			)
			(layer "F.SilkS")
		)
		(fp_line
			(start -0.3 0.7)
			(end 0.3 0.7)
			(stroke
				(width 0.15)
				(type solid)
			)
			(layer "F.SilkS")
		)
		(fp_rect
			(start 1.95 -0.9)
			(end -1.95 0.9)
			(stroke
				(width 0.05)
				(type default)
			)
			(fill no)
			(layer "F.CrtYd")
		)
		(fp_rect
			(start -0.95 -0.675)
			(end 0.95 0.675)
			(stroke
				(width 0.15)
				(type solid)
			)
			(fill no)
			(layer "F.Fab")
		)
		(fp_text user "License: Apache-2.0"
			(at -1.9 4.947 90)
			(layer "F.Fab")
			(effects
				(font
					(size 0.7 0.7)
					(thickness 0.15)
				)
				(justify left bottom)
			)
		)
		(fp_text user "${REFERENCE}"
			(at -1.9 3.947 90)
			(layer "F.Fab")
			(effects
				(font
					(size 0.7 0.7)
					(thickness 0.15)
				)
				(justify left bottom)
			)
		)
		(fp_text user "Author: Antmicro"
			(at -1.9 5.947 90)
			(layer "F.Fab")
			(effects
				(font
					(size 0.7 0.7)
					(thickness 0.15)
				)
				(justify left bottom)
			)
		)
		(pad "1" smd roundrect
			(at -1.1 0 90)
			(size 1.2 1.3)
			(layers "F.Cu" "F.Mask" "F.Paste")
			(roundrect_rratio 0.25)
			(net 1 "GND")
			(pintype "passive")
		)
		(pad "2" smd roundrect
			(at 1.1 0 90)
			(size 1.2 1.3)
			(layers "F.Cu" "F.Mask" "F.Paste")
			(roundrect_rratio 0.25)
			(net 13 "VCC")
			(pintype "passive")
		)
	)
)
